# S9S_MB_2U (Grand Teton) — schematic netlist excerpt (pin names and nets, part order shuffled) for the footprints in the layout excerpt that follows; sources: Cadence DE-HDL packaged netlist, KiCad conversion of 03242023_DA0F0TMBIJ0_F0T_Motherboard_J_brd_V01_OCP.brd

U211  74LVC2G07DW7  74LVC2G07DW-7 IC  pkg SOT363_0-65_2X1-25XC  page 156
  \1a\  = OCP_SFF_PRSNT0_R_N
  GND  = GND
  \2a\  = OCP_SFF_PRSNT1_R_N
  \2y\  = HP_LVC3_OCP_V3_1_PRSNT2_N_R
  VCC  = P3V3_AUX
  \1y\  = HP_LVC3_OCP_V3_1_PRSNT2_N_R

Q154  MOSFET_NCH_DUAL  PJT138K IC  pkg SOT363XD  page 144
  S1  = GND
  G1  = PRSNT_CABLE_GPU_A3_N
  D2  = PRSNT_CABLE_GPU_A3_ISO_N
  S2  = GND
  G2  = PRSNT_CABLE_GPU_A3
  D1  = PRSNT_CABLE_GPU_A3

(kicad_pcb
	(version 20260206)
	(generator "pcbnew")
	(generator_version "10.0")
	(general
		(thickness 1.6)
		(legacy_teardrops no)
	)
	(paper "A4")
	(title_block
		(title "03242023_DA0F0TMBIJ0_F0T_Motherboard_J_brd_V01_OCP.brd")
		(comment 1 "Grand Teton / footprints 1244-1245 of 6105")
	)
	(layers
		(0 "F.Cu" signal "TOP")
		(4 "In1.Cu" signal "GND")
		(6 "In2.Cu" signal "IN1")
		(8 "In3.Cu" signal "GND1")
		(10 "In4.Cu" signal "IN2")
		(12 "In5.Cu" signal "GND2")
		(14 "In6.Cu" signal "IN3")
		(16 "In7.Cu" signal "GND3")
		(18 "In8.Cu" signal "VCC")
		(20 "In9.Cu" signal "VCC1")
		(22 "In10.Cu" signal "GND4")
		(24 "In11.Cu" signal "IN4")
		(26 "In12.Cu" signal "GND5")
		(28 "In13.Cu" signal "IN5")
		(30 "In14.Cu" signal "GND6")
		(32 "In15.Cu" signal "IN6")
		(34 "In16.Cu" signal "GND7")
		(2 "B.Cu" signal "BOTTOM")
		(9 "F.Adhes" user "F.Adhesive")
		(11 "B.Adhes" user "B.Adhesive")
		(13 "F.Paste" user "Package Geometry/Pastemask Top")
		(15 "B.Paste" user "Package Geometry/Pastemask Bottom")
		(5 "F.SilkS" user "Ref Des/Silkscreen Top")
		(7 "B.SilkS" user "Ref Des/Silkscreen Bottom")
		(1 "F.Mask" user "Board Geometry/Soldermask Top")
		(3 "B.Mask" user "Board Geometry/Soldermask Bottom")
		(17 "Dwgs.User" user "User.Drawings")
		(19 "Cmts.User" user "User.Comments")
		(21 "Eco1.User" user "User.Eco1")
		(23 "Eco2.User" user "User.Eco2")
		(25 "Edge.Cuts" user "Board Geometry/Outline")
		(27 "Margin" user)
		(31 "F.CrtYd" user "Package Geometry/Place Bound Top")
		(29 "B.CrtYd" user "Package Geometry/Place Bound Bottom")
		(35 "F.Fab" user "Ref Des/Assembly Top")
		(33 "B.Fab" user "Ref Des/Assembly Bottom")
	)
	(footprint ""
		(layer "F.Cu")
		(at 361.44454 -412.9913 180)
		(property "Reference" "Q154"
			(at -1.8923 -2.470912 0)
			(unlocked yes)
			(layer "F.SilkS")
			(effects
				(font
					(size 0.7874 0.5842)
					(thickness 0.1524)
				)
				(justify left)
			)
		)
		(property "Value" ""
			(at 0 0 180)
			(layer "F.Fab")
			(effects
				(font
					(size 1.27 1.27)
				)
			)
		)
		(duplicate_pad_numbers_are_jumpers no)
		(fp_line
			(start 1.332738 1.100074)
			(end -1.332738 1.100074)
			(stroke
				(width 0.1524)
				(type default)
			)
			(layer "F.SilkS")
		)
		(fp_line
			(start 1.332738 -1.100074)
			(end 1.332738 1.100074)
			(stroke
				(width 0.1524)
				(type default)
			)
			(layer "F.SilkS")
		)
		(fp_line
			(start 0.4826 -1.100074)
			(end 1.332738 -1.100074)
			(stroke
				(width 0.1524)
				(type default)
			)
			(layer "F.SilkS")
		)
		(fp_line
			(start 0 -0.541274)
			(end 0.4826 -1.100074)
			(stroke
				(width 0.1524)
				(type default)
			)
			(layer "F.SilkS")
		)
		(fp_line
			(start -0.4826 -1.100074)
			(end 0 -0.541274)
			(stroke
				(width 0.1524)
				(type default)
			)
			(layer "F.SilkS")
		)
		(fp_line
			(start -1.332738 1.100074)
			(end -1.332738 -1.100074)
			(stroke
				(width 0.1524)
				(type default)
			)
			(layer "F.SilkS")
		)
		(fp_line
			(start -1.332738 -1.100074)
			(end -0.4826 -1.100074)
			(stroke
				(width 0.1524)
				(type default)
			)
			(layer "F.SilkS")
		)
		(fp_poly
			(pts
				(xy -2.422398 -1.07442) (xy -1.925828 -1.570736) (xy -1.67767 -0.826008)
			)
			(stroke
				(width 0)
				(type default)
			)
			(fill yes)
			(layer "F.SilkS")
		)
		(fp_line
			(start 0.674878 1.100074)
			(end -0.674878 1.100074)
			(stroke
				(width 0.1)
				(type default)
			)
			(layer "F.Fab")
		)
		(fp_line
			(start 0.674878 -1.100074)
			(end 0.674878 1.100074)
			(stroke
				(width 0.1)
				(type default)
			)
			(layer "F.Fab")
		)
		(fp_line
			(start -0.674878 1.100074)
			(end -0.674878 -1.100074)
			(stroke
				(width 0.1)
				(type default)
			)
			(layer "F.Fab")
		)
		(fp_line
			(start -0.674878 -1.100074)
			(end 0.674878 -1.100074)
			(stroke
				(width 0.1)
				(type default)
			)
			(layer "F.Fab")
		)
		(fp_poly
			(pts
				(xy -2.2352 -0.298958) (xy -2.2352 -1.001014) (xy -1.533144 -0.649986)
			)
			(stroke
				(width 0)
				(type default)
			)
			(fill yes)
			(layer "F.Fab")
		)
		(pad "1" smd rect
			(at -0.94996 -0.649986 270)
			(size 0.4318 0.508)
			(layers "F.Cu" "F.Mask" "F.Paste")
			(net "GND")
		)
		(pad "2" smd rect
			(at -0.94996 0 270)
			(size 0.4318 0.508)
			(layers "F.Cu" "F.Mask" "F.Paste")
			(net "PRSNT_CABLE_GPU_A3_N")
		)
		(pad "3" smd rect
			(at -0.94996 0.649986 270)
			(size 0.4318 0.508)
			(layers "F.Cu" "F.Mask" "F.Paste")
			(net "PRSNT_CABLE_GPU_A3_ISO_N")
		)
		(pad "4" smd rect
			(at 0.94996 0.649986 270)
			(size 0.4318 0.508)
			(layers "F.Cu" "F.Mask" "F.Paste")
			(net "GND")
		)
		(pad "5" smd rect
			(at 0.94996 0 270)
			(size 0.4318 0.508)
			(layers "F.Cu" "F.Mask" "F.Paste")
			(net "PRSNT_CABLE_GPU_A3")
		)
		(pad "6" smd rect
			(at 0.94996 -0.649986 270)
			(size 0.4318 0.508)
			(layers "F.Cu" "F.Mask" "F.Paste")
			(net "PRSNT_CABLE_GPU_A3")
		)
	)
	(footprint ""
		(layer "F.Cu")
		(at 457.684632 -107.018836)
		(property "Reference" "U211"
			(at -1.4732 -1.768348 0)
			(unlocked yes)
			(layer "F.SilkS")
			(effects
				(font
					(size 0.7874 0.5842)
					(thickness 0.1524)
				)
				(justify left)
			)
		)
		(property "Value" ""
			(at 0 0 0)
			(layer "F.Fab")
			(effects
				(font
					(size 1.27 1.27)
				)
			)
		)
		(duplicate_pad_numbers_are_jumpers no)
		(fp_line
			(start -1.38176 -1.100074)
			(end -1.38176 1.100074)
			(stroke
				(width 0.1524)
				(type default)
			)
			(layer "F.SilkS")
		)
		(fp_line
			(start -1.38176 1.100074)
			(end 1.38176 1.100074)
			(stroke
				(width 0.1524)
				(type default)
			)
			(layer "F.SilkS")
		)
		(fp_line
			(start -0.592074 -1.100074)
			(end -1.38176 -1.100074)
			(stroke
				(width 0.1524)
				(type default)
			)
			(layer "F.SilkS")
		)
		(fp_line
			(start 0 -0.508)
			(end -0.592074 -1.100074)
			(stroke
				(width 0.1524)
				(type default)
			)
			(layer "F.SilkS")
		)
		(fp_line
			(start 0.592074 -1.100074)
			(end 0 -0.508)
			(stroke
				(width 0.1524)
				(type default)
			)
			(layer "F.SilkS")
		)
		(fp_line
			(start 1.38176 -1.100074)
			(end 0.592074 -1.100074)
			(stroke
				(width 0.1524)
				(type default)
			)
			(layer "F.SilkS")
		)
		(fp_line
			(start 1.38176 1.100074)
			(end 1.38176 -1.100074)
			(stroke
				(width 0.1524)
				(type default)
			)
			(layer "F.SilkS")
		)
		(fp_poly
			(pts
				(xy -1.50241 -0.649986) (xy -1.9431 -0.429768) (xy -1.9431 -0.870204)
			)
			(stroke
				(width 0)
				(type default)
			)
			(fill yes)
			(layer "F.SilkS")
		)
		(fp_line
			(start -0.674878 -1.100074)
			(end -0.674878 1.100074)
			(stroke
				(width 0.1)
				(type default)
			)
			(layer "F.Fab")
		)
		(fp_line
			(start -0.674878 1.100074)
			(end 0.674878 1.100074)
			(stroke
				(width 0.1)
				(type default)
			)
			(layer "F.Fab")
		)
		(fp_line
			(start 0.674878 -1.100074)
			(end -0.674878 -1.100074)
			(stroke
				(width 0.1)
				(type default)
			)
			(layer "F.Fab")
		)
		(fp_line
			(start 0.674878 1.100074)
			(end 0.674878 -1.100074)
			(stroke
				(width 0.1)
				(type default)
			)
			(layer "F.Fab")
		)
		(fp_poly
			(pts
				(xy -1.9431 -0.870204) (xy -1.50241 -0.649986) (xy -1.9431 -0.429768)
			)
			(stroke
				(width 0)
				(type default)
			)
			(fill yes)
			(layer "F.Fab")
		)
		(pad "1" smd rect
			(at -0.94996 -0.649986 270)
			(size 0.4318 0.6096)
			(layers "F.Cu" "F.Mask" "F.Paste")
			(net "OCP_SFF_PRSNT0_R_N")
		)
		(pad "2" smd rect
			(at -0.94996 0 270)
			(size 0.4318 0.6096)
			(layers "F.Cu" "F.Mask" "F.Paste")
			(net "GND")
		)
		(pad "3" smd rect
			(at -0.94996 0.649986 270)
			(size 0.4318 0.6096)
			(layers "F.Cu" "F.Mask" "F.Paste")
			(net "OCP_SFF_PRSNT1_R_N")
		)
		(pad "4" smd rect
			(at 0.94996 0.649986 270)
			(size 0.4318 0.6096)
			(layers "F.Cu" "F.Mask" "F.Paste")
			(net "HP_LVC3_OCP_V3_1_PRSNT2_N_R")
		)
		(pad "5" smd rect
			(at 0.94996 0 270)
			(size 0.4318 0.6096)
			(layers "F.Cu" "F.Mask" "F.Paste")
			(net "P3V3_AUX")
		)
		(pad "6" smd rect
			(at 0.94996 -0.649986 270)
			(size 0.4318 0.6096)
			(layers "F.Cu" "F.Mask" "F.Paste")
			(net "HP_LVC3_OCP_V3_1_PRSNT2_N_R")
		)
	)
)
